(kicad_pcb
	(version 20260206)
	(generator "pcbnew")
	(generator_version "10.0")
	(general
		(thickness 1.6)
		(legacy_teardrops no)
	)
	(paper "A4")
	(title_block
		(title "01162023_DA0F0TEBIF0_F0T_Expander_BD_F_brd_V02_OCP.brd")
		(comment 1 "Grand Teton / footprints 4518-4523 of 9728")
	)
	(layers
		(0 "F.Cu" signal "TOP")
		(4 "In1.Cu" signal "GND")
		(6 "In2.Cu" signal "VCC")
		(8 "In3.Cu" signal "VCC1")
		(10 "In4.Cu" signal "GND1")
		(12 "In5.Cu" signal "IN1")
		(14 "In6.Cu" signal "GND2")
		(16 "In7.Cu" signal "IN2")
		(18 "In8.Cu" signal "GND3")
		(20 "In9.Cu" signal "IN3")
		(22 "In10.Cu" signal "GND4")
		(24 "In11.Cu" signal "IN4")
		(26 "In12.Cu" signal "GND5")
		(28 "In13.Cu" signal "IN5")
		(30 "In14.Cu" signal "GND6")
		(32 "In15.Cu" signal "IN6")
		(34 "In16.Cu" signal "GND7")
		(2 "B.Cu" signal "BOTTOM")
		(9 "F.Adhes" user "F.Adhesive")
		(11 "B.Adhes" user "B.Adhesive")
		(13 "F.Paste" user "Package Geometry/Pastemask Top")
		(15 "B.Paste" user "Package Geometry/Pastemask Bottom")
		(5 "F.SilkS" user "Ref Des/Silkscreen Top")
		(7 "B.SilkS" user "Ref Des/Silkscreen Bottom")
		(1 "F.Mask" user "Board Geometry/Soldermask Top")
		(3 "B.Mask" user "Board Geometry/Soldermask Bottom")
		(17 "Dwgs.User" user "User.Drawings")
		(19 "Cmts.User" user "User.Comments")
		(21 "Eco1.User" user "User.Eco1")
		(23 "Eco2.User" user "User.Eco2")
		(25 "Edge.Cuts" user "Board Geometry/Outline")
		(27 "Margin" user)
		(31 "F.CrtYd" user "Package Geometry/Place Bound Top")
		(29 "B.CrtYd" user "Package Geometry/Place Bound Bottom")
		(35 "F.Fab" user "Ref Des/Assembly Top")
		(33 "B.Fab" user "Ref Des/Assembly Bottom")
	)
	(footprint ""
		(layer "F.Cu")
		(at 143.030194 -290.805108 -90)
		(property "Reference" "C3209"
			(at 0 0 270)
			(layer "F.SilkS")
			(hide yes)
			(effects
				(font
					(size 1.27 1.27)
				)
			)
		)
		(property "Value" ""
			(at 0 0 270)
			(layer "F.Fab")
			(effects
				(font
					(size 1.27 1.27)
				)
			)
		)
		(duplicate_pad_numbers_are_jumpers no)
		(fp_line
			(start -1.2954 0.5842)
			(end -1.2954 -0.5842)
			(stroke
				(width 0.1524)
				(type default)
			)
			(layer "F.SilkS")
		)
		(fp_line
			(start 1.2954 0.5842)
			(end -1.2954 0.5842)
			(stroke
				(width 0.1524)
				(type default)
			)
			(layer "F.SilkS")
		)
		(fp_line
			(start -1.2954 -0.5842)
			(end 1.2954 -0.5842)
			(stroke
				(width 0.1524)
				(type default)
			)
			(layer "F.SilkS")
		)
		(fp_line
			(start 1.2954 -0.5842)
			(end 1.2954 0.5842)
			(stroke
				(width 0.1524)
				(type default)
			)
			(layer "F.SilkS")
		)
		(fp_line
			(start -0.8636 0.4572)
			(end -0.8636 0.4064)
			(stroke
				(width 0.1)
				(type default)
			)
			(layer "F.Fab")
		)
		(fp_line
			(start 0.8636 0.4572)
			(end -0.8636 0.4572)
			(stroke
				(width 0.1)
				(type default)
			)
			(layer "F.Fab")
		)
		(fp_line
			(start -1.1938 0.4064)
			(end -1.1938 -0.4064)
			(stroke
				(width 0.1)
				(type default)
			)
			(layer "F.Fab")
		)
		(fp_line
			(start -0.8636 0.4064)
			(end -1.1938 0.4064)
			(stroke
				(width 0.1)
				(type default)
			)
			(layer "F.Fab")
		)
		(fp_line
			(start 0.8636 0.4064)
			(end 0.8636 0.4572)
			(stroke
				(width 0.1)
				(type default)
			)
			(layer "F.Fab")
		)
		(fp_line
			(start 1.1938 0.4064)
			(end 0.8636 0.4064)
			(stroke
				(width 0.1)
				(type default)
			)
			(layer "F.Fab")
		)
		(fp_line
			(start -1.1938 -0.4064)
			(end -0.8636 -0.4064)
			(stroke
				(width 0.1)
				(type default)
			)
			(layer "F.Fab")
		)
		(fp_line
			(start -0.8636 -0.4064)
			(end -0.8636 -0.4572)
			(stroke
				(width 0.1)
				(type default)
			)
			(layer "F.Fab")
		)
		(fp_line
			(start 0.8636 -0.4064)
			(end 1.1938 -0.4064)
			(stroke
				(width 0.1)
				(type default)
			)
			(layer "F.Fab")
		)
		(fp_line
			(start 1.1938 -0.4064)
			(end 1.1938 0.4064)
			(stroke
				(width 0.1)
				(type default)
			)
			(layer "F.Fab")
		)
		(fp_line
			(start -0.8636 -0.4572)
			(end 0.8636 -0.4572)
			(stroke
				(width 0.1)
				(type default)
			)
			(layer "F.Fab")
		)
		(fp_line
			(start 0.8636 -0.4572)
			(end 0.8636 -0.4064)
			(stroke
				(width 0.1)
				(type default)
			)
			(layer "F.Fab")
		)
		(pad "1" smd rect
			(at -0.7366 0 180)
			(size 0.7112 0.8128)
			(layers "F.Cu" "F.Mask" "F.Paste")
			(net "P1V8_PLL0_PEX1")
		)
		(pad "2" smd rect
			(at 0.7366 0 180)
			(size 0.7112 0.8128)
			(layers "F.Cu" "F.Mask" "F.Paste")
			(net "GND")
		)
	)
	(footprint ""
		(layer "F.Cu")
		(at 161.346896 -38.49116 180)
		(property "Reference" "R6076"
			(at 0 0 180)
			(layer "F.SilkS")
			(hide yes)
			(effects
				(font
					(size 1.27 1.27)
				)
			)
		)
		(property "Value" ""
			(at 0 0 180)
			(layer "F.Fab")
			(effects
				(font
					(size 1.27 1.27)
				)
			)
		)
		(duplicate_pad_numbers_are_jumpers no)
		(fp_line
			(start 0.7874 0.4064)
			(end -0.7874 0.4064)
			(stroke
				(width 0.1524)
				(type default)
			)
			(layer "F.SilkS")
		)
		(fp_line
			(start 0.7874 -0.4064)
			(end 0.7874 0.4064)
			(stroke
				(width 0.1524)
				(type default)
			)
			(layer "F.SilkS")
		)
		(fp_line
			(start -0.7874 0.4064)
			(end -0.7874 -0.4064)
			(stroke
				(width 0.1524)
				(type default)
			)
			(layer "F.SilkS")
		)
		(fp_line
			(start -0.7874 -0.4064)
			(end 0.7874 -0.4064)
			(stroke
				(width 0.1524)
				(type default)
			)
			(layer "F.SilkS")
		)
		(fp_line
			(start 0.67945 0.3048)
			(end 0.120396 0.3048)
			(stroke
				(width 0.1)
				(type default)
			)
			(layer "F.Fab")
		)
		(fp_line
			(start 0.67945 -0.3048)
			(end 0.67945 0.3048)
			(stroke
				(width 0.1)
				(type default)
			)
			(layer "F.Fab")
		)
		(fp_line
			(start 0.12065 -0.2794)
			(end 0.12065 -0.3048)
			(stroke
				(width 0.1)
				(type default)
			)
			(layer "F.Fab")
		)
		(fp_line
			(start 0.12065 -0.3048)
			(end 0.67945 -0.3048)
			(stroke
				(width 0.1)
				(type default)
			)
			(layer "F.Fab")
		)
		(fp_line
			(start 0.120396 0.3048)
			(end 0.120396 0.2794)
			(stroke
				(width 0.1)
				(type default)
			)
			(layer "F.Fab")
		)
		(fp_line
			(start 0.120396 0.2794)
			(end -0.12065 0.2794)
			(stroke
				(width 0.1)
				(type default)
			)
			(layer "F.Fab")
		)
		(fp_line
			(start -0.12065 0.3048)
			(end -0.67945 0.3048)
			(stroke
				(width 0.1)
				(type default)
			)
			(layer "F.Fab")
		)
		(fp_line
			(start -0.12065 0.2794)
			(end -0.12065 0.3048)
			(stroke
				(width 0.1)
				(type default)
			)
			(layer "F.Fab")
		)
		(fp_line
			(start -0.12065 -0.2794)
			(end 0.12065 -0.2794)
			(stroke
				(width 0.1)
				(type default)
			)
			(layer "F.Fab")
		)
		(fp_line
			(start -0.12065 -0.305054)
			(end -0.12065 -0.2794)
			(stroke
				(width 0.1)
				(type default)
			)
			(layer "F.Fab")
		)
		(fp_line
			(start -0.67945 0.3048)
			(end -0.67945 -0.305054)
			(stroke
				(width 0.1)
				(type default)
			)
			(layer "F.Fab")
		)
		(fp_line
			(start -0.67945 -0.305054)
			(end -0.12065 -0.305054)
			(stroke
				(width 0.1)
				(type default)
			)
			(layer "F.Fab")
		)
		(pad "1" smd circle
			(at -0.40005 0 180)
			(size 0 0)
			(layers "F.Cu" "F.Mask" "F.Paste")
			(net "P3V3_SSD6_PG_G1")
		)
		(pad "2" smd circle
			(at 0.40005 0 180)
			(size 0 0)
			(layers "F.Cu" "F.Mask" "F.Paste")
			(net "GND")
		)
	)
	(footprint ""
		(layer "F.Cu")
		(at 223.45396 -239.446054 -90)
		(property "Reference" "R6218"
			(at 0 0 270)
			(layer "F.SilkS")
			(hide yes)
			(effects
				(font
					(size 1.27 1.27)
				)
			)
		)
		(property "Value" ""
			(at 0 0 270)
			(layer "F.Fab")
			(effects
				(font
					(size 1.27 1.27)
				)
			)
		)
		(duplicate_pad_numbers_are_jumpers no)
		(fp_line
			(start -0.7874 0.4064)
			(end -0.7874 -0.4064)
			(stroke
				(width 0.1524)
				(type default)
			)
			(layer "F.SilkS")
		)
		(fp_line
			(start 0.7874 0.4064)
			(end -0.7874 0.4064)
			(stroke
				(width 0.1524)
				(type default)
			)
			(layer "F.SilkS")
		)
		(fp_line
			(start -0.7874 -0.4064)
			(end 0.7874 -0.4064)
			(stroke
				(width 0.1524)
				(type default)
			)
			(layer "F.SilkS")
		)
		(fp_line
			(start 0.7874 -0.4064)
			(end 0.7874 0.4064)
			(stroke
				(width 0.1524)
				(type default)
			)
			(layer "F.SilkS")
		)
		(fp_line
			(start -0.67945 0.3048)
			(end -0.67945 -0.305054)
			(stroke
				(width 0.1)
				(type default)
			)
			(layer "F.Fab")
		)
		(fp_line
			(start -0.12065 0.3048)
			(end -0.67945 0.3048)
			(stroke
				(width 0.1)
				(type default)
			)
			(layer "F.Fab")
		)
		(fp_line
			(start 0.120396 0.3048)
			(end 0.120396 0.2794)
			(stroke
				(width 0.1)
				(type default)
			)
			(layer "F.Fab")
		)
		(fp_line
			(start 0.67945 0.3048)
			(end 0.120396 0.3048)
			(stroke
				(width 0.1)
				(type default)
			)
			(layer "F.Fab")
		)
		(fp_line
			(start -0.12065 0.2794)
			(end -0.12065 0.3048)
			(stroke
				(width 0.1)
				(type default)
			)
			(layer "F.Fab")
		)
		(fp_line
			(start 0.120396 0.2794)
			(end -0.12065 0.2794)
			(stroke
				(width 0.1)
				(type default)
			)
			(layer "F.Fab")
		)
		(fp_line
			(start -0.12065 -0.2794)
			(end 0.12065 -0.2794)
			(stroke
				(width 0.1)
				(type default)
			)
			(layer "F.Fab")
		)
		(fp_line
			(start 0.12065 -0.2794)
			(end 0.12065 -0.3048)
			(stroke
				(width 0.1)
				(type default)
			)
			(layer "F.Fab")
		)
		(fp_line
			(start 0.12065 -0.3048)
			(end 0.67945 -0.3048)
			(stroke
				(width 0.1)
				(type default)
			)
			(layer "F.Fab")
		)
		(fp_line
			(start 0.67945 -0.3048)
			(end 0.67945 0.3048)
			(stroke
				(width 0.1)
				(type default)
			)
			(layer "F.Fab")
		)
		(fp_line
			(start -0.67945 -0.305054)
			(end -0.12065 -0.305054)
			(stroke
				(width 0.1)
				(type default)
			)
			(layer "F.Fab")
		)
		(fp_line
			(start -0.12065 -0.305054)
			(end -0.12065 -0.2794)
			(stroke
				(width 0.1)
				(type default)
			)
			(layer "F.Fab")
		)
		(pad "1" smd circle
			(at -0.40005 0 270)
			(size 0 0)
			(layers "F.Cu" "F.Mask" "F.Paste")
			(net "BIC_UART_BIC_SEL_R")
		)
		(pad "2" smd circle
			(at 0.40005 0 270)
			(size 0 0)
			(layers "F.Cu" "F.Mask" "F.Paste")
			(net "GND")
		)
	)
	(footprint ""
		(layer "F.Cu")
		(at 194.367912 -53.051456)
		(property "Reference" "R4463"
			(at 0 0 0)
			(layer "F.SilkS")
			(hide yes)
			(effects
				(font
					(size 1.27 1.27)
				)
			)
		)
		(property "Value" ""
			(at 0 0 0)
			(layer "F.Fab")
			(effects
				(font
					(size 1.27 1.27)
				)
			)
		)
		(duplicate_pad_numbers_are_jumpers no)
		(fp_line
			(start -0.7874 -0.4064)
			(end 0.7874 -0.4064)
			(stroke
				(width 0.1524)
				(type default)
			)
			(layer "F.SilkS")
		)
		(fp_line
			(start -0.7874 0.4064)
			(end -0.7874 -0.4064)
			(stroke
				(width 0.1524)
				(type default)
			)
			(layer "F.SilkS")
		)
		(fp_line
			(start 0.7874 -0.4064)
			(end 0.7874 0.4064)
			(stroke
				(width 0.1524)
				(type default)
			)
			(layer "F.SilkS")
		)
		(fp_line
			(start 0.7874 0.4064)
			(end -0.7874 0.4064)
			(stroke
				(width 0.1524)
				(type default)
			)
			(layer "F.SilkS")
		)
		(fp_line
			(start -0.67945 -0.305054)
			(end -0.12065 -0.305054)
			(stroke
				(width 0.1)
				(type default)
			)
			(layer "F.Fab")
		)
		(fp_line
			(start -0.67945 0.3048)
			(end -0.67945 -0.305054)
			(stroke
				(width 0.1)
				(type default)
			)
			(layer "F.Fab")
		)
		(fp_line
			(start -0.12065 -0.305054)
			(end -0.12065 -0.2794)
			(stroke
				(width 0.1)
				(type default)
			)
			(layer "F.Fab")
		)
		(fp_line
			(start -0.12065 -0.2794)
			(end 0.12065 -0.2794)
			(stroke
				(width 0.1)
				(type default)
			)
			(layer "F.Fab")
		)
		(fp_line
			(start -0.12065 0.2794)
			(end -0.12065 0.3048)
			(stroke
				(width 0.1)
				(type default)
			)
			(layer "F.Fab")
		)
		(fp_line
			(start -0.12065 0.3048)
			(end -0.67945 0.3048)
			(stroke
				(width 0.1)
				(type default)
			)
			(layer "F.Fab")
		)
		(fp_line
			(start 0.120396 0.2794)
			(end -0.12065 0.2794)
			(stroke
				(width 0.1)
				(type default)
			)
			(layer "F.Fab")
		)
		(fp_line
			(start 0.120396 0.3048)
			(end 0.120396 0.2794)
			(stroke
				(width 0.1)
				(type default)
			)
			(layer "F.Fab")
		)
		(fp_line
			(start 0.12065 -0.3048)
			(end 0.67945 -0.3048)
			(stroke
				(width 0.1)
				(type default)
			)
			(layer "F.Fab")
		)
		(fp_line
			(start 0.12065 -0.2794)
			(end 0.12065 -0.3048)
			(stroke
				(width 0.1)
				(type default)
			)
			(layer "F.Fab")
		)
		(fp_line
			(start 0.67945 -0.3048)
			(end 0.67945 0.3048)
			(stroke
				(width 0.1)
				(type default)
			)
			(layer "F.Fab")
		)
		(fp_line
			(start 0.67945 0.3048)
			(end 0.120396 0.3048)
			(stroke
				(width 0.1)
				(type default)
			)
			(layer "F.Fab")
		)
		(pad "1" smd circle
			(at -0.40005 0)
			(size 0 0)
			(layers "F.Cu" "F.Mask" "F.Paste")
			(net "PWRGD_P12V_SSD6")
		)
		(pad "2" smd circle
			(at 0.40005 0)
			(size 0 0)
			(layers "F.Cu" "F.Mask" "F.Paste")
			(net "PWRGD_P12V_SSD6_R")
		)
	)
	(footprint ""
		(layer "F.Cu")
		(at 338.498434 -5.747258)
		(property "Reference" "R1704"
			(at 0 0 0)
			(layer "F.SilkS")
			(hide yes)
			(effects
				(font
					(size 1.27 1.27)
				)
			)
		)
		(property "Value" ""
			(at 0 0 0)
			(layer "F.Fab")
			(effects
				(font
					(size 1.27 1.27)
				)
			)
		)
		(duplicate_pad_numbers_are_jumpers no)
		(fp_line
			(start -0.7874 -0.4064)
			(end 0.7874 -0.4064)
			(stroke
				(width 0.1524)
				(type default)
			)
			(layer "F.SilkS")
		)
		(fp_line
			(start -0.7874 0.4064)
			(end -0.7874 -0.4064)
			(stroke
				(width 0.1524)
				(type default)
			)
			(layer "F.SilkS")
		)
		(fp_line
			(start 0.7874 -0.4064)
			(end 0.7874 0.4064)
			(stroke
				(width 0.1524)
				(type default)
			)
			(layer "F.SilkS")
		)
		(fp_line
			(start 0.7874 0.4064)
			(end -0.7874 0.4064)
			(stroke
				(width 0.1524)
				(type default)
			)
			(layer "F.SilkS")
		)
		(fp_line
			(start -0.67945 -0.305054)
			(end -0.12065 -0.305054)
			(stroke
				(width 0.1)
				(type default)
			)
			(layer "F.Fab")
		)
		(fp_line
			(start -0.67945 0.3048)
			(end -0.67945 -0.305054)
			(stroke
				(width 0.1)
				(type default)
			)
			(layer "F.Fab")
		)
		(fp_line
			(start -0.12065 -0.305054)
			(end -0.12065 -0.2794)
			(stroke
				(width 0.1)
				(type default)
			)
			(layer "F.Fab")
		)
		(fp_line
			(start -0.12065 -0.2794)
			(end 0.12065 -0.2794)
			(stroke
				(width 0.1)
				(type default)
			)
			(layer "F.Fab")
		)
		(fp_line
			(start -0.12065 0.2794)
			(end -0.12065 0.3048)
			(stroke
				(width 0.1)
				(type default)
			)
			(layer "F.Fab")
		)
		(fp_line
			(start -0.12065 0.3048)
			(end -0.67945 0.3048)
			(stroke
				(width 0.1)
				(type default)
			)
			(layer "F.Fab")
		)
		(fp_line
			(start 0.120396 0.2794)
			(end -0.12065 0.2794)
			(stroke
				(width 0.1)
				(type default)
			)
			(layer "F.Fab")
		)
		(fp_line
			(start 0.120396 0.3048)
			(end 0.120396 0.2794)
			(stroke
				(width 0.1)
				(type default)
			)
			(layer "F.Fab")
		)
		(fp_line
			(start 0.12065 -0.3048)
			(end 0.67945 -0.3048)
			(stroke
				(width 0.1)
				(type default)
			)
			(layer "F.Fab")
		)
		(fp_line
			(start 0.12065 -0.2794)
			(end 0.12065 -0.3048)
			(stroke
				(width 0.1)
				(type default)
			)
			(layer "F.Fab")
		)
		(fp_line
			(start 0.67945 -0.3048)
			(end 0.67945 0.3048)
			(stroke
				(width 0.1)
				(type default)
			)
			(layer "F.Fab")
		)
		(fp_line
			(start 0.67945 0.3048)
			(end 0.120396 0.3048)
			(stroke
				(width 0.1)
				(type default)
			)
			(layer "F.Fab")
		)
		(pad "1" smd circle
			(at -0.40005 0)
			(size 0 0)
			(layers "F.Cu" "F.Mask" "F.Paste")
			(net "SMB_SSD11_ISO_EN")
		)
		(pad "2" smd circle
			(at 0.40005 0)
			(size 0 0)
			(layers "F.Cu" "F.Mask" "F.Paste")
			(net "P3V3_AUX")
		)
	)
	(footprint ""
		(layer "F.Cu")
		(at 240.389156 -228.57206 180)
		(property "Reference" "R6761"
			(at 0 0 180)
			(layer "F.SilkS")
			(hide yes)
			(effects
				(font
					(size 1.27 1.27)
				)
			)
		)
		(property "Value" ""
			(at 0 0 180)
			(layer "F.Fab")
			(effects
				(font
					(size 1.27 1.27)
				)
			)
		)
		(duplicate_pad_numbers_are_jumpers no)
		(fp_line
			(start 0.7874 -0.4064)
			(end 0.7874 0.4064)
			(stroke
				(width 0.1524)
				(type default)
			)
			(layer "F.SilkS")
		)
		(fp_line
			(start 0.67945 0.3048)
			(end 0.120396 0.3048)
			(stroke
				(width 0.1)
				(type default)
			)
			(layer "F.Fab")
		)
		(fp_line
			(start 0.67945 -0.3048)
			(end 0.67945 0.3048)
			(stroke
				(width 0.1)
				(type default)
			)
			(layer "F.Fab")
		)
		(fp_line
			(start 0.12065 -0.2794)
			(end 0.12065 -0.3048)
			(stroke
				(width 0.1)
				(type default)
			)
			(layer "F.Fab")
		)
		(fp_line
			(start 0.12065 -0.3048)
			(end 0.67945 -0.3048)
			(stroke
				(width 0.1)
				(type default)
			)
			(layer "F.Fab")
		)
		(fp_line
			(start 0.120396 0.3048)
			(end 0.120396 0.2794)
			(stroke
				(width 0.1)
				(type default)
			)
			(layer "F.Fab")
		)
		(fp_line
			(start 0.120396 0.2794)
			(end -0.12065 0.2794)
			(stroke
				(width 0.1)
				(type default)
			)
			(layer "F.Fab")
		)
		(fp_line
			(start -0.12065 0.3048)
			(end -0.67945 0.3048)
			(stroke
				(width 0.1)
				(type default)
			)
			(layer "F.Fab")
		)
		(fp_line
			(start -0.12065 0.2794)
			(end -0.12065 0.3048)
			(stroke
				(width 0.1)
				(type default)
			)
			(layer "F.Fab")
		)
		(fp_line
			(start -0.12065 -0.2794)
			(end 0.12065 -0.2794)
			(stroke
				(width 0.1)
				(type default)
			)
			(layer "F.Fab")
		)
		(fp_line
			(start -0.12065 -0.305054)
			(end -0.12065 -0.2794)
			(stroke
				(width 0.1)
				(type default)
			)
			(layer "F.Fab")
		)
		(fp_line
			(start -0.67945 0.3048)
			(end -0.67945 -0.305054)
			(stroke
				(width 0.1)
				(type default)
			)
			(layer "F.Fab")
		)
		(fp_line
			(start -0.67945 -0.305054)
			(end -0.12065 -0.305054)
			(stroke
				(width 0.1)
				(type default)
			)
			(layer "F.Fab")
		)
		(pad "1" smd circle
			(at -0.40005 0 180)
			(size 0 0)
			(layers "F.Cu" "F.Mask" "F.Paste")
			(net "USB2_BIC_DN")
		)
		(pad "2" smd circle
			(at 0.40005 0 180)
			(size 0 0)
			(layers "F.Cu" "F.Mask" "F.Paste")
			(net "GND")
		)
	)
)
